# S9S_MB_2U (Grand Teton) — schematic netlist excerpt (pin names and nets, part order shuffled) for the footprints in the layout excerpt that follows; sources: Cadence DE-HDL packaged netlist, KiCad conversion of 03242023_DA0F0TMBIJ0_F0T_Motherboard_J_brd_V01_OCP.brd

R3577  Q_RES  33.2 1% CHIP  pkg 0402LF  page 172 : A = SMB_INA230_5_3V3AUX_SDA_R ; B = SMB_INA230_5_3V3AUX_SDA_R1
PC644  Q_CAP  1UF 25V 10% X6S  pkg C0402  page 299 : A = PVPP_HBM_CPU1_VCC ; B = GND

(kicad_pcb
	(version 20260206)
	(generator "pcbnew")
	(generator_version "10.0")
	(general
		(thickness 1.6)
		(legacy_teardrops no)
	)
	(paper "A4")
	(title_block
		(title "03242023_DA0F0TMBIJ0_F0T_Motherboard_J_brd_V01_OCP.brd")
		(comment 1 "Grand Teton / footprints 1024-1025 of 6105")
	)
	(layers
		(0 "F.Cu" signal "TOP")
		(4 "In1.Cu" signal "GND")
		(6 "In2.Cu" signal "IN1")
		(8 "In3.Cu" signal "GND1")
		(10 "In4.Cu" signal "IN2")
		(12 "In5.Cu" signal "GND2")
		(14 "In6.Cu" signal "IN3")
		(16 "In7.Cu" signal "GND3")
		(18 "In8.Cu" signal "VCC")
		(20 "In9.Cu" signal "VCC1")
		(22 "In10.Cu" signal "GND4")
		(24 "In11.Cu" signal "IN4")
		(26 "In12.Cu" signal "GND5")
		(28 "In13.Cu" signal "IN5")
		(30 "In14.Cu" signal "GND6")
		(32 "In15.Cu" signal "IN6")
		(34 "In16.Cu" signal "GND7")
		(2 "B.Cu" signal "BOTTOM")
		(9 "F.Adhes" user "F.Adhesive")
		(11 "B.Adhes" user "B.Adhesive")
		(13 "F.Paste" user "Package Geometry/Pastemask Top")
		(15 "B.Paste" user "Package Geometry/Pastemask Bottom")
		(5 "F.SilkS" user "Ref Des/Silkscreen Top")
		(7 "B.SilkS" user "Ref Des/Silkscreen Bottom")
		(1 "F.Mask" user "Board Geometry/Soldermask Top")
		(3 "B.Mask" user "Board Geometry/Soldermask Bottom")
		(17 "Dwgs.User" user "User.Drawings")
		(19 "Cmts.User" user "User.Comments")
		(21 "Eco1.User" user "User.Eco1")
		(23 "Eco2.User" user "User.Eco2")
		(25 "Edge.Cuts" user "Board Geometry/Outline")
		(27 "Margin" user)
		(31 "F.CrtYd" user "Package Geometry/Place Bound Top")
		(29 "B.CrtYd" user "Package Geometry/Place Bound Bottom")
		(35 "F.Fab" user "Ref Des/Assembly Top")
		(33 "B.Fab" user "Ref Des/Assembly Bottom")
	)
	(footprint ""
		(layer "F.Cu")
		(at 128.548384 -359.871518 -90)
		(property "Reference" "PC644"
			(at 0 0 270)
			(layer "F.SilkS")
			(hide yes)
			(effects
				(font
					(size 1.27 1.27)
				)
			)
		)
		(property "Value" ""
			(at 0 0 270)
			(layer "F.Fab")
			(effects
				(font
					(size 1.27 1.27)
				)
			)
		)
		(duplicate_pad_numbers_are_jumpers no)
		(fp_line
			(start -0.7874 0.4064)
			(end -0.7874 -0.4064)
			(stroke
				(width 0.1524)
				(type default)
			)
			(layer "F.SilkS")
		)
		(fp_line
			(start 0.7874 0.4064)
			(end -0.7874 0.4064)
			(stroke
				(width 0.1524)
				(type default)
			)
			(layer "F.SilkS")
		)
		(fp_line
			(start -0.7874 -0.4064)
			(end 0.7874 -0.4064)
			(stroke
				(width 0.1524)
				(type default)
			)
			(layer "F.SilkS")
		)
		(fp_line
			(start 0.7874 -0.4064)
			(end 0.7874 0.4064)
			(stroke
				(width 0.1524)
				(type default)
			)
			(layer "F.SilkS")
		)
		(fp_line
			(start -0.67945 0.3048)
			(end -0.67945 -0.305054)
			(stroke
				(width 0.1)
				(type default)
			)
			(layer "F.Fab")
		)
		(fp_line
			(start -0.12065 0.3048)
			(end -0.67945 0.3048)
			(stroke
				(width 0.1)
				(type default)
			)
			(layer "F.Fab")
		)
		(fp_line
			(start 0.120396 0.3048)
			(end 0.120396 0.2794)
			(stroke
				(width 0.1)
				(type default)
			)
			(layer "F.Fab")
		)
		(fp_line
			(start 0.67945 0.3048)
			(end 0.120396 0.3048)
			(stroke
				(width 0.1)
				(type default)
			)
			(layer "F.Fab")
		)
		(fp_line
			(start -0.12065 0.2794)
			(end -0.12065 0.3048)
			(stroke
				(width 0.1)
				(type default)
			)
			(layer "F.Fab")
		)
		(fp_line
			(start 0.120396 0.2794)
			(end -0.12065 0.2794)
			(stroke
				(width 0.1)
				(type default)
			)
			(layer "F.Fab")
		)
		(fp_line
			(start -0.12065 -0.2794)
			(end 0.12065 -0.2794)
			(stroke
				(width 0.1)
				(type default)
			)
			(layer "F.Fab")
		)
		(fp_line
			(start 0.12065 -0.2794)
			(end 0.12065 -0.3048)
			(stroke
				(width 0.1)
				(type default)
			)
			(layer "F.Fab")
		)
		(fp_line
			(start 0.12065 -0.3048)
			(end 0.67945 -0.3048)
			(stroke
				(width 0.1)
				(type default)
			)
			(layer "F.Fab")
		)
		(fp_line
			(start 0.67945 -0.3048)
			(end 0.67945 0.3048)
			(stroke
				(width 0.1)
				(type default)
			)
			(layer "F.Fab")
		)
		(fp_line
			(start -0.67945 -0.305054)
			(end -0.12065 -0.305054)
			(stroke
				(width 0.1)
				(type default)
			)
			(layer "F.Fab")
		)
		(fp_line
			(start -0.12065 -0.305054)
			(end -0.12065 -0.2794)
			(stroke
				(width 0.1)
				(type default)
			)
			(layer "F.Fab")
		)
		(pad "1" smd circle
			(at -0.40005 0 270)
			(size 0 0)
			(layers "F.Cu" "F.Mask" "F.Paste")
			(net "PVPP_HBM_CPU1_VCC")
		)
		(pad "2" smd circle
			(at 0.40005 0 270)
			(size 0 0)
			(layers "F.Cu" "F.Mask" "F.Paste")
			(net "GND")
		)
	)
	(footprint ""
		(layer "F.Cu")
		(at 213.54288 -32.857948 180)
		(property "Reference" "R3577"
			(at 0 0 180)
			(layer "F.SilkS")
			(hide yes)
			(effects
				(font
					(size 1.27 1.27)
				)
			)
		)
		(property "Value" ""
			(at 0 0 180)
			(layer "F.Fab")
			(effects
				(font
					(size 1.27 1.27)
				)
			)
		)
		(duplicate_pad_numbers_are_jumpers no)
		(fp_line
			(start 0.7874 0.4064)
			(end -0.7874 0.4064)
			(stroke
				(width 0.1524)
				(type default)
			)
			(layer "F.SilkS")
		)
		(fp_line
			(start 0.7874 -0.4064)
			(end 0.7874 0.4064)
			(stroke
				(width 0.1524)
				(type default)
			)
			(layer "F.SilkS")
		)
		(fp_line
			(start -0.7874 0.4064)
			(end -0.7874 -0.4064)
			(stroke
				(width 0.1524)
				(type default)
			)
			(layer "F.SilkS")
		)
		(fp_line
			(start -0.7874 -0.4064)
			(end 0.7874 -0.4064)
			(stroke
				(width 0.1524)
				(type default)
			)
			(layer "F.SilkS")
		)
		(fp_line
			(start 0.67945 0.3048)
			(end 0.120396 0.3048)
			(stroke
				(width 0.1)
				(type default)
			)
			(layer "F.Fab")
		)
		(fp_line
			(start 0.67945 -0.3048)
			(end 0.67945 0.3048)
			(stroke
				(width 0.1)
				(type default)
			)
			(layer "F.Fab")
		)
		(fp_line
			(start 0.12065 -0.2794)
			(end 0.12065 -0.3048)
			(stroke
				(width 0.1)
				(type default)
			)
			(layer "F.Fab")
		)
		(fp_line
			(start 0.12065 -0.3048)
			(end 0.67945 -0.3048)
			(stroke
				(width 0.1)
				(type default)
			)
			(layer "F.Fab")
		)
		(fp_line
			(start 0.120396 0.3048)
			(end 0.120396 0.2794)
			(stroke
				(width 0.1)
				(type default)
			)
			(layer "F.Fab")
		)
		(fp_line
			(start 0.120396 0.2794)
			(end -0.12065 0.2794)
			(stroke
				(width 0.1)
				(type default)
			)
			(layer "F.Fab")
		)
		(fp_line
			(start -0.12065 0.3048)
			(end -0.67945 0.3048)
			(stroke
				(width 0.1)
				(type default)
			)
			(layer "F.Fab")
		)
		(fp_line
			(start -0.12065 0.2794)
			(end -0.12065 0.3048)
			(stroke
				(width 0.1)
				(type default)
			)
			(layer "F.Fab")
		)
		(fp_line
			(start -0.12065 -0.2794)
			(end 0.12065 -0.2794)
			(stroke
				(width 0.1)
				(type default)
			)
			(layer "F.Fab")
		)
		(fp_line
			(start -0.12065 -0.305054)
			(end -0.12065 -0.2794)
			(stroke
				(width 0.1)
				(type default)
			)
			(layer "F.Fab")
		)
		(fp_line
			(start -0.67945 0.3048)
			(end -0.67945 -0.305054)
			(stroke
				(width 0.1)
				(type default)
			)
			(layer "F.Fab")
		)
		(fp_line
			(start -0.67945 -0.305054)
			(end -0.12065 -0.305054)
			(stroke
				(width 0.1)
				(type default)
			)
			(layer "F.Fab")
		)
		(pad "1" smd circle
			(at -0.40005 0 180)
			(size 0 0)
			(layers "F.Cu" "F.Mask" "F.Paste")
			(net "SMB_INA230_5_3V3AUX_SDA_R")
		)
		(pad "2" smd circle
			(at 0.40005 0 180)
			(size 0 0)
			(layers "F.Cu" "F.Mask" "F.Paste")
			(net "SMB_INA230_5_3V3AUX_SDA_R1")
		)
	)
)
